(kicad_pcb
	(version 20221018)
	(generator pcbnew)
	(general
    (thickness 1.7403)
  )
	(paper "A4")
	(title_block
    (title "Data Center RDIMM DDR4 Tester")
    (date "2024-09-30")
    (rev "1.2.4")
		(comment 9 "footprints 133-136 of 690")
	)
	(layers
    (0 "F.Cu" signal)
    (1 "In1.Cu" power)
    (2 "In2.Cu" signal)
    (3 "In3.Cu" power)
    (4 "In4.Cu" power)
    (5 "In5.Cu" signal)
    (6 "In6.Cu" power)
    (7 "In7.Cu" signal)
    (8 "In8.Cu" power)
    (9 "In9.Cu" signal)
    (10 "In10.Cu" power)
    (31 "B.Cu" signal)
    (32 "B.Adhes" user "B.Adhesive")
    (33 "F.Adhes" user "F.Adhesive")
    (34 "B.Paste" user)
    (35 "F.Paste" user)
    (36 "B.SilkS" user "B.Silkscreen")
    (37 "F.SilkS" user "F.Silkscreen")
    (38 "B.Mask" user)
    (39 "F.Mask" user)
    (40 "Dwgs.User" user "User.Drawings")
    (41 "Cmts.User" user "User.Comments")
    (42 "Eco1.User" user "User.Eco1")
    (43 "Eco2.User" user "User.Eco2")
    (44 "Edge.Cuts" user)
    (45 "Margin" user)
    (46 "B.CrtYd" user "B.Courtyard")
    (47 "F.CrtYd" user "F.Courtyard")
    (48 "B.Fab" user)
    (49 "F.Fab" user)
  )
	(footprint "data-center-rdimm-ddr4-tester-footprints:LED_0603_1608Metric_G" (layer "F.Cu")
    (at 251.7 95 180)
    (descr "LED SMD 0603 Green")
    (tags "LED SMD 0603 Green")
    (property "Author" "Antmicro")
    (property "License" "Apache-2.0")
    (property "MPN" "KP-1608CGCK")
    (property "Manufacturer" "Kingbright")
    (property "Sheetfile" "interfaces.kicad_sch")
    (property "Sheetname" "Interfaces")
    (attr smd)
    (fp_text reference "D6" (at 0.79 -1.26 180) (layer "F.SilkS")
        (effects (font (size 0.7 0.7) (thickness 0.15)) (justify left bottom))
    )
    (fp_text value "LED_G_0603_KP-1608CGCK" (at 0 1.6 180) (layer "F.Fab") hide
        (effects (font (size 0.7 0.7) (thickness 0.15)) (justify left bottom))
    )
    (fp_text user "License: Apache-2.0" (at -1.31 5.769 180) (layer "F.Fab") hide
        (effects (font (size 0.7 0.7) (thickness 0.15)) (justify left bottom))
    )
    (fp_text user "${REFERENCE}" (at -1.31 3.769 180) (layer "F.Fab") hide
        (effects (font (size 0.7 0.7) (thickness 0.15)) (justify left bottom))
    )
    (fp_text user "Author: Antmicro" (at -1.31 4.769 180) (layer "F.Fab") hide
        (effects (font (size 0.7 0.7) (thickness 0.15)) (justify left bottom))
    )
    (fp_line (start -0.27 -0.35) (end 0.27 -0.35)
      (stroke (width 0.15) (type solid)) (layer "F.SilkS"))
    (fp_line (start -0.27 0.351) (end 0.27 0.351)
      (stroke (width 0.15) (type solid)) (layer "F.SilkS"))
    (fp_line (start -0.106328 -0.200008) (end -0.106328 0.199992)
      (stroke (width 0.1) (type solid)) (layer "F.SilkS"))
    (fp_line (start -0.106328 -0.200008) (end 0.093672 -0.000008)
      (stroke (width 0.1) (type solid)) (layer "F.SilkS"))
    (fp_line (start -0.106328 -0.000008) (end -0.29 0)
      (stroke (width 0.1) (type solid)) (layer "F.SilkS"))
    (fp_line (start 0.093672 -0.200008) (end 0.093672 0.199992)
      (stroke (width 0.1) (type solid)) (layer "F.SilkS"))
    (fp_line (start 0.093672 -0.000008) (end -0.106328 0.199992)
      (stroke (width 0.1) (type solid)) (layer "F.SilkS"))
    (fp_line (start 0.093672 -0.000008) (end 0.293672 -0.000008)
      (stroke (width 0.1) (type solid)) (layer "F.SilkS"))
    (fp_line (start 1.25 0.32) (end 1.25 -0.32)
      (stroke (width 0.15) (type solid)) (layer "F.SilkS"))
    (fp_rect (start 1.26 0.65) (end -1.26 -0.65)
      (stroke (width 0.05) (type solid)) (fill none) (layer "F.CrtYd"))
    (fp_line (start -0.599 0) (end -0.201 0)
      (stroke (width 0.15) (type solid)) (layer "F.Fab"))
    (fp_line (start -0.201 -0.2) (end -0.201 0)
      (stroke (width 0.15) (type solid)) (layer "F.Fab"))
    (fp_line (start -0.201 0) (end -0.201 0.202)
      (stroke (width 0.15) (type solid)) (layer "F.Fab"))
    (fp_line (start -0.201 0.202) (end 0.101 0)
      (stroke (width 0.15) (type solid)) (layer "F.Fab"))
    (fp_line (start 0.101 0) (end -0.201 -0.2)
      (stroke (width 0.15) (type solid)) (layer "F.Fab"))
    (fp_line (start 0.199 -0.2) (end 0.199 -0.1)
      (stroke (width 0.15) (type solid)) (layer "F.Fab"))
    (fp_line (start 0.199 0) (end 0.597 0)
      (stroke (width 0.15) (type solid)) (layer "F.Fab"))
    (fp_line (start 0.199 0.202) (end 0.199 -0.1)
      (stroke (width 0.15) (type solid)) (layer "F.Fab"))
    (fp_rect (start -0.848 -0.4) (end 0.85 0.402)
      (stroke (width 0.15) (type solid)) (fill none) (layer "F.Fab"))
    (pad "1" smd rect (at -0.75 0) (size 0.8 0.8) (layers "F.Cu" "F.Paste" "F.Mask")
      (net 143 "3V3_SYS") (pinfunction "1") (pintype "passive"))
    (pad "2" smd rect (at 0.75 0) (size 0.8 0.8) (layers "F.Cu" "F.Paste" "F.Mask")
      (net 64 "Net-(D6-Pad2)") (pinfunction "2") (pintype "passive"))
  )
	(footprint "data-center-rdimm-ddr4-tester-footprints:LED_0603_1608Metric_G" (layer "F.Cu")
    (at 251.7 101 180)
    (descr "LED SMD 0603 Green")
    (tags "LED SMD 0603 Green")
    (property "Author" "Antmicro")
    (property "License" "Apache-2.0")
    (property "MPN" "KP-1608CGCK")
    (property "Manufacturer" "Kingbright")
    (property "Sheetfile" "interfaces.kicad_sch")
    (property "Sheetname" "Interfaces")
    (attr smd)
    (fp_text reference "D7" (at 0.79 -1.35 180) (layer "F.SilkS")
        (effects (font (size 0.7 0.7) (thickness 0.15)) (justify left bottom))
    )
    (fp_text value "LED_G_0603_KP-1608CGCK" (at 0 1.6 180) (layer "F.Fab") hide
        (effects (font (size 0.7 0.7) (thickness 0.15)) (justify left bottom))
    )
    (fp_text user "License: Apache-2.0" (at -1.31 5.769 180) (layer "F.Fab") hide
        (effects (font (size 0.7 0.7) (thickness 0.15)) (justify left bottom))
    )
    (fp_text user "Author: Antmicro" (at -1.31 4.769 180) (layer "F.Fab") hide
        (effects (font (size 0.7 0.7) (thickness 0.15)) (justify left bottom))
    )
    (fp_text user "${REFERENCE}" (at -1.31 3.769 180) (layer "F.Fab") hide
        (effects (font (size 0.7 0.7) (thickness 0.15)) (justify left bottom))
    )
    (fp_line (start -0.27 -0.35) (end 0.27 -0.35)
      (stroke (width 0.15) (type solid)) (layer "F.SilkS"))
    (fp_line (start -0.27 0.351) (end 0.27 0.351)
      (stroke (width 0.15) (type solid)) (layer "F.SilkS"))
    (fp_line (start -0.106328 -0.200008) (end -0.106328 0.199992)
      (stroke (width 0.1) (type solid)) (layer "F.SilkS"))
    (fp_line (start -0.106328 -0.200008) (end 0.093672 -0.000008)
      (stroke (width 0.1) (type solid)) (layer "F.SilkS"))
    (fp_line (start -0.106328 -0.000008) (end -0.29 0)
      (stroke (width 0.1) (type solid)) (layer "F.SilkS"))
    (fp_line (start 0.093672 -0.200008) (end 0.093672 0.199992)
      (stroke (width 0.1) (type solid)) (layer "F.SilkS"))
    (fp_line (start 0.093672 -0.000008) (end -0.106328 0.199992)
      (stroke (width 0.1) (type solid)) (layer "F.SilkS"))
    (fp_line (start 0.093672 -0.000008) (end 0.293672 -0.000008)
      (stroke (width 0.1) (type solid)) (layer "F.SilkS"))
    (fp_line (start 1.25 0.32) (end 1.25 -0.32)
      (stroke (width 0.15) (type solid)) (layer "F.SilkS"))
    (fp_rect (start 1.26 0.65) (end -1.26 -0.65)
      (stroke (width 0.05) (type solid)) (fill none) (layer "F.CrtYd"))
    (fp_line (start -0.599 0) (end -0.201 0)
      (stroke (width 0.15) (type solid)) (layer "F.Fab"))
    (fp_line (start -0.201 -0.2) (end -0.201 0)
      (stroke (width 0.15) (type solid)) (layer "F.Fab"))
    (fp_line (start -0.201 0) (end -0.201 0.202)
      (stroke (width 0.15) (type solid)) (layer "F.Fab"))
    (fp_line (start -0.201 0.202) (end 0.101 0)
      (stroke (width 0.15) (type solid)) (layer "F.Fab"))
    (fp_line (start 0.101 0) (end -0.201 -0.2)
      (stroke (width 0.15) (type solid)) (layer "F.Fab"))
    (fp_line (start 0.199 -0.2) (end 0.199 -0.1)
      (stroke (width 0.15) (type solid)) (layer "F.Fab"))
    (fp_line (start 0.199 0) (end 0.597 0)
      (stroke (width 0.15) (type solid)) (layer "F.Fab"))
    (fp_line (start 0.199 0.202) (end 0.199 -0.1)
      (stroke (width 0.15) (type solid)) (layer "F.Fab"))
    (fp_rect (start -0.848 -0.4) (end 0.85 0.402)
      (stroke (width 0.15) (type solid)) (fill none) (layer "F.Fab"))
    (pad "1" smd rect (at -0.75 0) (size 0.8 0.8) (layers "F.Cu" "F.Paste" "F.Mask")
      (net 143 "3V3_SYS") (pinfunction "1") (pintype "passive"))
    (pad "2" smd rect (at 0.75 0) (size 0.8 0.8) (layers "F.Cu" "F.Paste" "F.Mask")
      (net 65 "Net-(D7-Pad2)") (pinfunction "2") (pintype "passive"))
  )
	(footprint "data-center-rdimm-ddr4-tester-footprints:LED_0603_1608Metric_G" (layer "F.Cu")
    (at 251.7 89 180)
    (descr "LED SMD 0603 Green")
    (tags "LED SMD 0603 Green")
    (property "Author" "Antmicro")
    (property "License" "Apache-2.0")
    (property "MPN" "KP-1608CGCK")
    (property "Manufacturer" "Kingbright")
    (property "Sheetfile" "interfaces.kicad_sch")
    (property "Sheetname" "Interfaces")
    (attr smd)
    (fp_text reference "D8" (at 0.8 -1.31 180) (layer "F.SilkS")
        (effects (font (size 0.7 0.7) (thickness 0.15)) (justify left bottom))
    )
    (fp_text value "LED_G_0603_KP-1608CGCK" (at 0 1.6 180) (layer "F.Fab") hide
        (effects (font (size 0.7 0.7) (thickness 0.15)) (justify left bottom))
    )
    (fp_text user "Author: Antmicro" (at -1.31 4.769 180) (layer "F.Fab") hide
        (effects (font (size 0.7 0.7) (thickness 0.15)) (justify left bottom))
    )
    (fp_text user "${REFERENCE}" (at -1.31 3.769 180) (layer "F.Fab") hide
        (effects (font (size 0.7 0.7) (thickness 0.15)) (justify left bottom))
    )
    (fp_text user "License: Apache-2.0" (at -1.31 5.769 180) (layer "F.Fab") hide
        (effects (font (size 0.7 0.7) (thickness 0.15)) (justify left bottom))
    )
    (fp_line (start -0.27 -0.35) (end 0.27 -0.35)
      (stroke (width 0.15) (type solid)) (layer "F.SilkS"))
    (fp_line (start -0.27 0.351) (end 0.27 0.351)
      (stroke (width 0.15) (type solid)) (layer "F.SilkS"))
    (fp_line (start -0.106328 -0.200008) (end -0.106328 0.199992)
      (stroke (width 0.1) (type solid)) (layer "F.SilkS"))
    (fp_line (start -0.106328 -0.200008) (end 0.093672 -0.000008)
      (stroke (width 0.1) (type solid)) (layer "F.SilkS"))
    (fp_line (start -0.106328 -0.000008) (end -0.29 0)
      (stroke (width 0.1) (type solid)) (layer "F.SilkS"))
    (fp_line (start 0.093672 -0.200008) (end 0.093672 0.199992)
      (stroke (width 0.1) (type solid)) (layer "F.SilkS"))
    (fp_line (start 0.093672 -0.000008) (end -0.106328 0.199992)
      (stroke (width 0.1) (type solid)) (layer "F.SilkS"))
    (fp_line (start 0.093672 -0.000008) (end 0.293672 -0.000008)
      (stroke (width 0.1) (type solid)) (layer "F.SilkS"))
    (fp_line (start 1.25 0.32) (end 1.25 -0.32)
      (stroke (width 0.15) (type solid)) (layer "F.SilkS"))
    (fp_rect (start 1.26 0.65) (end -1.26 -0.65)
      (stroke (width 0.05) (type solid)) (fill none) (layer "F.CrtYd"))
    (fp_line (start -0.599 0) (end -0.201 0)
      (stroke (width 0.15) (type solid)) (layer "F.Fab"))
    (fp_line (start -0.201 -0.2) (end -0.201 0)
      (stroke (width 0.15) (type solid)) (layer "F.Fab"))
    (fp_line (start -0.201 0) (end -0.201 0.202)
      (stroke (width 0.15) (type solid)) (layer "F.Fab"))
    (fp_line (start -0.201 0.202) (end 0.101 0)
      (stroke (width 0.15) (type solid)) (layer "F.Fab"))
    (fp_line (start 0.101 0) (end -0.201 -0.2)
      (stroke (width 0.15) (type solid)) (layer "F.Fab"))
    (fp_line (start 0.199 -0.2) (end 0.199 -0.1)
      (stroke (width 0.15) (type solid)) (layer "F.Fab"))
    (fp_line (start 0.199 0) (end 0.597 0)
      (stroke (width 0.15) (type solid)) (layer "F.Fab"))
    (fp_line (start 0.199 0.202) (end 0.199 -0.1)
      (stroke (width 0.15) (type solid)) (layer "F.Fab"))
    (fp_rect (start -0.848 -0.4) (end 0.85 0.402)
      (stroke (width 0.15) (type solid)) (fill none) (layer "F.Fab"))
    (pad "1" smd rect (at -0.75 0) (size 0.8 0.8) (layers "F.Cu" "F.Paste" "F.Mask")
      (net 143 "3V3_SYS") (pinfunction "1") (pintype "passive"))
    (pad "2" smd rect (at 0.75 0) (size 0.8 0.8) (layers "F.Cu" "F.Paste" "F.Mask")
      (net 66 "Net-(D8-Pad2)") (pinfunction "2") (pintype "passive"))
  )
	(footprint "data-center-rdimm-ddr4-tester-footprints:LED_0603_1608Metric_G" (layer "F.Cu")
    (at 251.7 83.1 180)
    (descr "LED SMD 0603 Green")
    (tags "LED SMD 0603 Green")
    (property "Author" "Antmicro")
    (property "License" "Apache-2.0")
    (property "MPN" "KP-1608CGCK")
    (property "Manufacturer" "Kingbright")
    (property "Sheetfile" "interfaces.kicad_sch")
    (property "Sheetname" "Interfaces")
    (attr smd)
    (fp_text reference "D9" (at 0.75 -1.32 180) (layer "F.SilkS")
        (effects (font (size 0.7 0.7) (thickness 0.15)) (justify left bottom))
    )
    (fp_text value "LED_G_0603_KP-1608CGCK" (at 0 1.6 180) (layer "F.Fab") hide
        (effects (font (size 0.7 0.7) (thickness 0.15)) (justify left bottom))
    )
    (fp_text user "License: Apache-2.0" (at -1.31 5.769 180) (layer "F.Fab") hide
        (effects (font (size 0.7 0.7) (thickness 0.15)) (justify left bottom))
    )
    (fp_text user "${REFERENCE}" (at -1.31 3.769 180) (layer "F.Fab") hide
        (effects (font (size 0.7 0.7) (thickness 0.15)) (justify left bottom))
    )
    (fp_text user "Author: Antmicro" (at -1.31 4.769 180) (layer "F.Fab") hide
        (effects (font (size 0.7 0.7) (thickness 0.15)) (justify left bottom))
    )
    (fp_line (start -0.27 -0.35) (end 0.27 -0.35)
      (stroke (width 0.15) (type solid)) (layer "F.SilkS"))
    (fp_line (start -0.27 0.351) (end 0.27 0.351)
      (stroke (width 0.15) (type solid)) (layer "F.SilkS"))
    (fp_line (start -0.106328 -0.200008) (end -0.106328 0.199992)
      (stroke (width 0.1) (type solid)) (layer "F.SilkS"))
    (fp_line (start -0.106328 -0.200008) (end 0.093672 -0.000008)
      (stroke (width 0.1) (type solid)) (layer "F.SilkS"))
    (fp_line (start -0.106328 -0.000008) (end -0.29 0)
      (stroke (width 0.1) (type solid)) (layer "F.SilkS"))
    (fp_line (start 0.093672 -0.200008) (end 0.093672 0.199992)
      (stroke (width 0.1) (type solid)) (layer "F.SilkS"))
    (fp_line (start 0.093672 -0.000008) (end -0.106328 0.199992)
      (stroke (width 0.1) (type solid)) (layer "F.SilkS"))
    (fp_line (start 0.093672 -0.000008) (end 0.293672 -0.000008)
      (stroke (width 0.1) (type solid)) (layer "F.SilkS"))
    (fp_line (start 1.25 0.32) (end 1.25 -0.32)
      (stroke (width 0.15) (type solid)) (layer "F.SilkS"))
    (fp_rect (start 1.26 0.65) (end -1.26 -0.65)
      (stroke (width 0.05) (type solid)) (fill none) (layer "F.CrtYd"))
    (fp_line (start -0.599 0) (end -0.201 0)
      (stroke (width 0.15) (type solid)) (layer "F.Fab"))
    (fp_line (start -0.201 -0.2) (end -0.201 0)
      (stroke (width 0.15) (type solid)) (layer "F.Fab"))
    (fp_line (start -0.201 0) (end -0.201 0.202)
      (stroke (width 0.15) (type solid)) (layer "F.Fab"))
    (fp_line (start -0.201 0.202) (end 0.101 0)
      (stroke (width 0.15) (type solid)) (layer "F.Fab"))
    (fp_line (start 0.101 0) (end -0.201 -0.2)
      (stroke (width 0.15) (type solid)) (layer "F.Fab"))
    (fp_line (start 0.199 -0.2) (end 0.199 -0.1)
      (stroke (width 0.15) (type solid)) (layer "F.Fab"))
    (fp_line (start 0.199 0) (end 0.597 0)
      (stroke (width 0.15) (type solid)) (layer "F.Fab"))
    (fp_line (start 0.199 0.202) (end 0.199 -0.1)
      (stroke (width 0.15) (type solid)) (layer "F.Fab"))
    (fp_rect (start -0.848 -0.4) (end 0.85 0.402)
      (stroke (width 0.15) (type solid)) (fill none) (layer "F.Fab"))
    (pad "1" smd rect (at -0.75 0) (size 0.8 0.8) (layers "F.Cu" "F.Paste" "F.Mask")
      (net 143 "3V3_SYS") (pinfunction "1") (pintype "passive"))
    (pad "2" smd rect (at 0.75 0) (size 0.8 0.8) (layers "F.Cu" "F.Paste" "F.Mask")
      (net 78 "Net-(D9-Pad2)") (pinfunction "2") (pintype "passive"))
  )
)
